(kicad_pcb
	(version 20260206)
	(generator "pcbnew")
	(generator_version "10.0")
	(general
		(thickness 1.6)
		(legacy_teardrops no)
	)
	(paper "A4")
	(title_block
		(title "04192023_DAF0TMB3IC0_F0TG_MB_C_brd_V02_OCP.brd")
		(comment 1 "Grand Teton / footprints 574-579 of 8354")
	)
	(layers
		(0 "F.Cu" signal "TOP")
		(4 "In1.Cu" signal "GND")
		(6 "In2.Cu" signal "IN1")
		(8 "In3.Cu" signal "GND1")
		(10 "In4.Cu" signal "IN2")
		(12 "In5.Cu" signal "GND2")
		(14 "In6.Cu" signal "IN3")
		(16 "In7.Cu" signal "GND3")
		(18 "In8.Cu" signal "VCC")
		(20 "In9.Cu" signal "VCC1")
		(22 "In10.Cu" signal "GND4")
		(24 "In11.Cu" signal "IN4")
		(26 "In12.Cu" signal "GND5")
		(28 "In13.Cu" signal "IN5")
		(30 "In14.Cu" signal "GND6")
		(32 "In15.Cu" signal "IN6")
		(34 "In16.Cu" signal "GND7")
		(2 "B.Cu" signal "BOTTOM")
		(9 "F.Adhes" user "F.Adhesive")
		(11 "B.Adhes" user "B.Adhesive")
		(13 "F.Paste" user "Package Geometry/Pastemask Top")
		(15 "B.Paste" user "Package Geometry/Pastemask Bottom")
		(5 "F.SilkS" user "Ref Des/Silkscreen Top")
		(7 "B.SilkS" user "Ref Des/Silkscreen Bottom")
		(1 "F.Mask" user "Board Geometry/Soldermask Top")
		(3 "B.Mask" user "Board Geometry/Soldermask Bottom")
		(17 "Dwgs.User" user "User.Drawings")
		(19 "Cmts.User" user "User.Comments")
		(21 "Eco1.User" user "User.Eco1")
		(23 "Eco2.User" user "User.Eco2")
		(25 "Edge.Cuts" user "Board Geometry/Outline")
		(27 "Margin" user)
		(31 "F.CrtYd" user "Package Geometry/Place Bound Top")
		(29 "B.CrtYd" user "Package Geometry/Place Bound Bottom")
		(35 "F.Fab" user "Ref Des/Assembly Top")
		(33 "B.Fab" user "Ref Des/Assembly Bottom")
	)
	(footprint ""
		(layer "F.Cu")
		(at 160.377886 -119.089424 180)
		(property "Reference" "R2219"
			(at 0 0 180)
			(layer "F.SilkS")
			(hide yes)
			(effects
				(font
					(size 1.27 1.27)
				)
			)
		)
		(property "Value" ""
			(at 0 0 180)
			(layer "F.Fab")
			(effects
				(font
					(size 1.27 1.27)
				)
			)
		)
		(duplicate_pad_numbers_are_jumpers no)
		(fp_line
			(start 0.7874 0.4064)
			(end -0.7874 0.4064)
			(stroke
				(width 0.1524)
				(type default)
			)
			(layer "F.SilkS")
		)
		(fp_line
			(start 0.7874 -0.4064)
			(end 0.7874 0.4064)
			(stroke
				(width 0.1524)
				(type default)
			)
			(layer "F.SilkS")
		)
		(fp_line
			(start -0.7874 0.4064)
			(end -0.7874 -0.4064)
			(stroke
				(width 0.1524)
				(type default)
			)
			(layer "F.SilkS")
		)
		(fp_line
			(start -0.7874 -0.4064)
			(end 0.7874 -0.4064)
			(stroke
				(width 0.1524)
				(type default)
			)
			(layer "F.SilkS")
		)
		(fp_line
			(start 0.67945 0.3048)
			(end 0.120396 0.3048)
			(stroke
				(width 0.1)
				(type default)
			)
			(layer "F.Fab")
		)
		(fp_line
			(start 0.67945 -0.3048)
			(end 0.67945 0.3048)
			(stroke
				(width 0.1)
				(type default)
			)
			(layer "F.Fab")
		)
		(fp_line
			(start 0.12065 -0.2794)
			(end 0.12065 -0.3048)
			(stroke
				(width 0.1)
				(type default)
			)
			(layer "F.Fab")
		)
		(fp_line
			(start 0.12065 -0.3048)
			(end 0.67945 -0.3048)
			(stroke
				(width 0.1)
				(type default)
			)
			(layer "F.Fab")
		)
		(fp_line
			(start 0.120396 0.3048)
			(end 0.120396 0.2794)
			(stroke
				(width 0.1)
				(type default)
			)
			(layer "F.Fab")
		)
		(fp_line
			(start 0.120396 0.2794)
			(end -0.12065 0.2794)
			(stroke
				(width 0.1)
				(type default)
			)
			(layer "F.Fab")
		)
		(fp_line
			(start -0.12065 0.3048)
			(end -0.67945 0.3048)
			(stroke
				(width 0.1)
				(type default)
			)
			(layer "F.Fab")
		)
		(fp_line
			(start -0.12065 0.2794)
			(end -0.12065 0.3048)
			(stroke
				(width 0.1)
				(type default)
			)
			(layer "F.Fab")
		)
		(fp_line
			(start -0.12065 -0.2794)
			(end 0.12065 -0.2794)
			(stroke
				(width 0.1)
				(type default)
			)
			(layer "F.Fab")
		)
		(fp_line
			(start -0.12065 -0.305054)
			(end -0.12065 -0.2794)
			(stroke
				(width 0.1)
				(type default)
			)
			(layer "F.Fab")
		)
		(fp_line
			(start -0.67945 0.3048)
			(end -0.67945 -0.305054)
			(stroke
				(width 0.1)
				(type default)
			)
			(layer "F.Fab")
		)
		(fp_line
			(start -0.67945 -0.305054)
			(end -0.12065 -0.305054)
			(stroke
				(width 0.1)
				(type default)
			)
			(layer "F.Fab")
		)
		(pad "1" smd circle
			(at -0.40005 0 180)
			(size 0 0)
			(layers "F.Cu" "F.Mask" "F.Paste")
			(net "P12V_AUX")
		)
		(pad "2" smd circle
			(at 0.40005 0 180)
			(size 0 0)
			(layers "F.Cu" "F.Mask" "F.Paste")
			(net "A_P12V_STBY_ADR_TRIGGER")
		)
	)
	(footprint ""
		(layer "F.Cu")
		(at 152.84958 -33.59658)
		(property "Reference" "R1522"
			(at 0 0 0)
			(layer "F.SilkS")
			(hide yes)
			(effects
				(font
					(size 1.27 1.27)
				)
			)
		)
		(property "Value" ""
			(at 0 0 0)
			(layer "F.Fab")
			(effects
				(font
					(size 1.27 1.27)
				)
			)
		)
		(duplicate_pad_numbers_are_jumpers no)
		(fp_line
			(start -0.7874 -0.4064)
			(end 0.7874 -0.4064)
			(stroke
				(width 0.1524)
				(type default)
			)
			(layer "F.SilkS")
		)
		(fp_line
			(start -0.7874 0.4064)
			(end -0.7874 -0.4064)
			(stroke
				(width 0.1524)
				(type default)
			)
			(layer "F.SilkS")
		)
		(fp_line
			(start 0.7874 -0.4064)
			(end 0.7874 0.4064)
			(stroke
				(width 0.1524)
				(type default)
			)
			(layer "F.SilkS")
		)
		(fp_line
			(start 0.7874 0.4064)
			(end -0.7874 0.4064)
			(stroke
				(width 0.1524)
				(type default)
			)
			(layer "F.SilkS")
		)
		(fp_line
			(start -0.67945 -0.305054)
			(end -0.12065 -0.305054)
			(stroke
				(width 0.1)
				(type default)
			)
			(layer "F.Fab")
		)
		(fp_line
			(start -0.67945 0.3048)
			(end -0.67945 -0.305054)
			(stroke
				(width 0.1)
				(type default)
			)
			(layer "F.Fab")
		)
		(fp_line
			(start -0.12065 -0.305054)
			(end -0.12065 -0.2794)
			(stroke
				(width 0.1)
				(type default)
			)
			(layer "F.Fab")
		)
		(fp_line
			(start -0.12065 -0.2794)
			(end 0.12065 -0.2794)
			(stroke
				(width 0.1)
				(type default)
			)
			(layer "F.Fab")
		)
		(fp_line
			(start -0.12065 0.2794)
			(end -0.12065 0.3048)
			(stroke
				(width 0.1)
				(type default)
			)
			(layer "F.Fab")
		)
		(fp_line
			(start -0.12065 0.3048)
			(end -0.67945 0.3048)
			(stroke
				(width 0.1)
				(type default)
			)
			(layer "F.Fab")
		)
		(fp_line
			(start 0.120396 0.2794)
			(end -0.12065 0.2794)
			(stroke
				(width 0.1)
				(type default)
			)
			(layer "F.Fab")
		)
		(fp_line
			(start 0.120396 0.3048)
			(end 0.120396 0.2794)
			(stroke
				(width 0.1)
				(type default)
			)
			(layer "F.Fab")
		)
		(fp_line
			(start 0.12065 -0.3048)
			(end 0.67945 -0.3048)
			(stroke
				(width 0.1)
				(type default)
			)
			(layer "F.Fab")
		)
		(fp_line
			(start 0.12065 -0.2794)
			(end 0.12065 -0.3048)
			(stroke
				(width 0.1)
				(type default)
			)
			(layer "F.Fab")
		)
		(fp_line
			(start 0.67945 -0.3048)
			(end 0.67945 0.3048)
			(stroke
				(width 0.1)
				(type default)
			)
			(layer "F.Fab")
		)
		(fp_line
			(start 0.67945 0.3048)
			(end 0.120396 0.3048)
			(stroke
				(width 0.1)
				(type default)
			)
			(layer "F.Fab")
		)
		(pad "1" smd circle
			(at -0.40005 0)
			(size 0 0)
			(layers "F.Cu" "F.Mask" "F.Paste")
			(net "HP_LVC3_OCP_V3_2_R_EN")
		)
		(pad "2" smd circle
			(at 0.40005 0)
			(size 0 0)
			(layers "F.Cu" "F.Mask" "F.Paste")
			(net "P12V_OCP_V3_2_BUF_EN_R")
		)
	)
	(footprint ""
		(layer "F.Cu")
		(at 429.4251 -400.987768 -90)
		(property "Reference" "R1057"
			(at 0 0 270)
			(layer "F.SilkS")
			(hide yes)
			(effects
				(font
					(size 1.27 1.27)
				)
			)
		)
		(property "Value" ""
			(at 0 0 270)
			(layer "F.Fab")
			(effects
				(font
					(size 1.27 1.27)
				)
			)
		)
		(duplicate_pad_numbers_are_jumpers no)
		(fp_line
			(start -0.32512 0.175006)
			(end -0.32512 -0.175006)
			(stroke
				(width 0.1)
				(type default)
			)
			(layer "F.Fab")
		)
		(fp_line
			(start 0.32512 0.175006)
			(end -0.32512 0.175006)
			(stroke
				(width 0.1)
				(type default)
			)
			(layer "F.Fab")
		)
		(fp_line
			(start -0.32512 -0.175006)
			(end 0.32512 -0.175006)
			(stroke
				(width 0.1)
				(type default)
			)
			(layer "F.Fab")
		)
		(fp_line
			(start 0.32512 -0.175006)
			(end 0.32512 0.175006)
			(stroke
				(width 0.1)
				(type default)
			)
			(layer "F.Fab")
		)
		(pad "1" smd rect
			(at -0.2667 0 270)
			(size 0.3048 0.381)
			(layers "F.Cu" "F.Mask" "F.Paste")
			(net "P1V8_CPU0_RT_1D")
		)
		(pad "2" smd rect
			(at 0.2667 0 90)
			(size 0.3048 0.381)
			(layers "F.Cu" "F.Mask" "F.Paste")
			(net "RT_CPU0_P2_ADDR2")
		)
	)
	(footprint ""
		(layer "F.Cu")
		(at 314.965588 0.002794)
		(property "Reference" "J73"
			(at -4.473448 1.284732 90)
			(unlocked yes)
			(layer "F.SilkS")
			(effects
				(font
					(size 0.7874 0.5842)
					(thickness 0.1524)
				)
				(justify left)
			)
		)
		(property "Value" ""
			(at 0 0 0)
			(layer "F.Fab")
			(effects
				(font
					(size 1.27 1.27)
				)
			)
		)
		(duplicate_pad_numbers_are_jumpers no)
		(fp_line
			(start -1.2192 -2.06756)
			(end 1.2192 -2.06756)
			(stroke
				(width 0.1524)
				(type default)
			)
			(layer "F.SilkS")
		)
		(fp_line
			(start -1.2192 2.06756)
			(end -1.2192 -2.06756)
			(stroke
				(width 0.1524)
				(type default)
			)
			(layer "F.SilkS")
		)
		(fp_line
			(start 1.2192 -2.06756)
			(end 1.2192 2.06756)
			(stroke
				(width 0.1524)
				(type default)
			)
			(layer "F.SilkS")
		)
		(fp_line
			(start 1.2192 2.06756)
			(end -1.2192 2.06756)
			(stroke
				(width 0.1524)
				(type default)
			)
			(layer "F.SilkS")
		)
		(pad "" np_thru_hole circle
			(at -2.8829 -1.27 270)
			(size 1.0414 1.0414)
			(drill 1.0414)
			(layers "*.Cu" "*.Mask")
			(clearance 0.381)
			(thermal_gap 0.381)
		)
		(pad "" np_thru_hole circle
			(at -2.8829 1.27 270)
			(size 1.0414 1.0414)
			(drill 1.0414)
			(layers "*.Cu" "*.Mask")
			(clearance 0.381)
			(thermal_gap 0.381)
		)
		(pad "" np_thru_hole circle
			(at 3.4671 -1.27 270)
			(size 1.0414 1.0414)
			(drill 1.0414)
			(layers "*.Cu" "*.Mask")
			(clearance 0.381)
			(thermal_gap 0.381)
		)
		(pad "" np_thru_hole circle
			(at 3.4671 1.27 270)
			(size 1.0414 1.0414)
			(drill 1.0414)
			(layers "*.Cu" "*.Mask")
			(clearance 0.381)
			(thermal_gap 0.381)
		)
		(pad "1" smd rect
			(at 0.8255 -0.249936 270)
			(size 0.3048 0.508)
			(layers "F.Cu" "F.Mask" "F.Paste")
			(net "DELTA_L_85_5INCH_IN3_DN")
		)
		(pad "2" smd rect
			(at 0.8255 0.249936 270)
			(size 0.3048 0.508)
			(layers "F.Cu" "F.Mask" "F.Paste")
			(net "DELTA_L_85_5INCH_IN3_DP")
		)
		(pad "3" smd circle
			(at 0 0)
			(size 0 0)
			(layers "F.Cu" "F.Mask" "F.Paste")
			(net "DELTA_L_GND_1")
		)
		(zone
			(layer "F.Cu")
			(hatch none 0.5)
			(connect_pads
				(clearance 0)
			)
			(min_thickness 0.25)
			(keepout
				(tracks not_allowed)
				(vias allowed)
				(pads allowed)
				(copperpour not_allowed)
				(footprints allowed)
			)
			(placement
				(enabled no)
				(sheetname "")
			)
			(fill
				(thermal_gap 0.5)
				(thermal_bridge_width 0.5)
				(island_removal_mode 0)
			)
			(polygon
				(pts
					(xy 316.083188 -0.545846) (xy 316.083188 -0.450342) (xy 315.486288 -0.450342) (xy 315.486288 -0.043942)
					(xy 316.083188 -0.043942) (xy 316.083188 0.04953) (xy 315.486288 0.04953) (xy 315.486288 0.45593)
					(xy 316.083188 0.45593) (xy 316.083188 0.551434) (xy 315.384688 0.551434) (xy 315.384688 -0.545846)
				)
			)
		)
		(zone
			(layers "F.Cu" "B.Cu" "In1.Cu" "In2.Cu" "In3.Cu" "In4.Cu" "In5.Cu" "In6.Cu"
				"In7.Cu" "In8.Cu" "In9.Cu" "In10.Cu" "In11.Cu" "In12.Cu" "In13.Cu" "In14.Cu"
				"In15.Cu" "In16.Cu"
			)
			(hatch none 0.5)
			(connect_pads
				(clearance 0)
			)
			(min_thickness 0.25)
			(keepout
				(tracks not_allowed)
				(vias allowed)
				(pads allowed)
				(copperpour not_allowed)
				(footprints allowed)
			)
			(placement
				(enabled no)
				(sheetname "")
			)
			(fill
				(thermal_gap 0.5)
				(thermal_bridge_width 0.5)
				(island_removal_mode 0)
			)
			(polygon
				(pts
					(arc
						(start 313.009788 -1.267206)
						(mid 311.155588 -1.267206)
						(end 313.009788 -1.267206)
					)
				)
			)
		)
		(zone
			(layers "F.Cu" "B.Cu" "In1.Cu" "In2.Cu" "In3.Cu" "In4.Cu" "In5.Cu" "In6.Cu"
				"In7.Cu" "In8.Cu" "In9.Cu" "In10.Cu" "In11.Cu" "In12.Cu" "In13.Cu" "In14.Cu"
				"In15.Cu" "In16.Cu"
			)
			(hatch none 0.5)
			(connect_pads
				(clearance 0)
			)
			(min_thickness 0.25)
			(keepout
				(tracks not_allowed)
				(vias allowed)
				(pads allowed)
				(copperpour not_allowed)
				(footprints allowed)
			)
			(placement
				(enabled no)
				(sheetname "")
			)
			(fill
				(thermal_gap 0.5)
				(thermal_bridge_width 0.5)
				(island_removal_mode 0)
			)
			(polygon
				(pts
					(arc
						(start 313.009788 1.272794)
						(mid 311.155588 1.272794)
						(end 313.009788 1.272794)
					)
				)
			)
		)
		(zone
			(layers "F.Cu" "B.Cu" "In1.Cu" "In2.Cu" "In3.Cu" "In4.Cu" "In5.Cu" "In6.Cu"
				"In7.Cu" "In8.Cu" "In9.Cu" "In10.Cu" "In11.Cu" "In12.Cu" "In13.Cu" "In14.Cu"
				"In15.Cu" "In16.Cu"
			)
			(hatch none 0.5)
			(connect_pads
				(clearance 0)
			)
			(min_thickness 0.25)
			(keepout
				(tracks not_allowed)
				(vias allowed)
				(pads allowed)
				(copperpour not_allowed)
				(footprints allowed)
			)
			(placement
				(enabled no)
				(sheetname "")
			)
			(fill
				(thermal_gap 0.5)
				(thermal_bridge_width 0.5)
				(island_removal_mode 0)
			)
			(polygon
				(pts
					(arc
						(start 319.359788 -1.267206)
						(mid 317.505588 -1.267206)
						(end 319.359788 -1.267206)
					)
				)
			)
		)
		(zone
			(layers "F.Cu" "B.Cu" "In1.Cu" "In2.Cu" "In3.Cu" "In4.Cu" "In5.Cu" "In6.Cu"
				"In7.Cu" "In8.Cu" "In9.Cu" "In10.Cu" "In11.Cu" "In12.Cu" "In13.Cu" "In14.Cu"
				"In15.Cu" "In16.Cu"
			)
			(hatch none 0.5)
			(connect_pads
				(clearance 0)
			)
			(min_thickness 0.25)
			(keepout
				(tracks not_allowed)
				(vias allowed)
				(pads allowed)
				(copperpour not_allowed)
				(footprints allowed)
			)
			(placement
				(enabled no)
				(sheetname "")
			)
			(fill
				(thermal_gap 0.5)
				(thermal_bridge_width 0.5)
				(island_removal_mode 0)
			)
			(polygon
				(pts
					(arc
						(start 319.359788 1.272794)
						(mid 317.505588 1.272794)
						(end 319.359788 1.272794)
					)
				)
			)
		)
	)
	(footprint ""
		(layer "F.Cu")
		(at 352.05543 -434.857652 180)
		(property "Reference" "C8"
			(at 0 0 180)
			(layer "F.SilkS")
			(hide yes)
			(effects
				(font
					(size 1.27 1.27)
				)
			)
		)
		(property "Value" ""
			(at 0 0 180)
			(layer "F.Fab")
			(effects
				(font
					(size 1.27 1.27)
				)
			)
		)
		(duplicate_pad_numbers_are_jumpers no)
		(fp_line
			(start 0.7874 0.4064)
			(end -0.7874 0.4064)
			(stroke
				(width 0.1524)
				(type default)
			)
			(layer "F.SilkS")
		)
		(fp_line
			(start 0.7874 -0.4064)
			(end 0.7874 0.4064)
			(stroke
				(width 0.1524)
				(type default)
			)
			(layer "F.SilkS")
		)
		(fp_line
			(start -0.7874 0.4064)
			(end -0.7874 -0.4064)
			(stroke
				(width 0.1524)
				(type default)
			)
			(layer "F.SilkS")
		)
		(fp_line
			(start -0.7874 -0.4064)
			(end 0.7874 -0.4064)
			(stroke
				(width 0.1524)
				(type default)
			)
			(layer "F.SilkS")
		)
		(fp_line
			(start 0.67945 0.3048)
			(end 0.120396 0.3048)
			(stroke
				(width 0.1)
				(type default)
			)
			(layer "F.Fab")
		)
		(fp_line
			(start 0.67945 -0.3048)
			(end 0.67945 0.3048)
			(stroke
				(width 0.1)
				(type default)
			)
			(layer "F.Fab")
		)
		(fp_line
			(start 0.12065 -0.2794)
			(end 0.12065 -0.3048)
			(stroke
				(width 0.1)
				(type default)
			)
			(layer "F.Fab")
		)
		(fp_line
			(start 0.12065 -0.3048)
			(end 0.67945 -0.3048)
			(stroke
				(width 0.1)
				(type default)
			)
			(layer "F.Fab")
		)
		(fp_line
			(start 0.120396 0.3048)
			(end 0.120396 0.2794)
			(stroke
				(width 0.1)
				(type default)
			)
			(layer "F.Fab")
		)
		(fp_line
			(start 0.120396 0.2794)
			(end -0.12065 0.2794)
			(stroke
				(width 0.1)
				(type default)
			)
			(layer "F.Fab")
		)
		(fp_line
			(start -0.12065 0.3048)
			(end -0.67945 0.3048)
			(stroke
				(width 0.1)
				(type default)
			)
			(layer "F.Fab")
		)
		(fp_line
			(start -0.12065 0.2794)
			(end -0.12065 0.3048)
			(stroke
				(width 0.1)
				(type default)
			)
			(layer "F.Fab")
		)
		(fp_line
			(start -0.12065 -0.2794)
			(end 0.12065 -0.2794)
			(stroke
				(width 0.1)
				(type default)
			)
			(layer "F.Fab")
		)
		(fp_line
			(start -0.12065 -0.305054)
			(end -0.12065 -0.2794)
			(stroke
				(width 0.1)
				(type default)
			)
			(layer "F.Fab")
		)
		(fp_line
			(start -0.67945 0.3048)
			(end -0.67945 -0.305054)
			(stroke
				(width 0.1)
				(type default)
			)
			(layer "F.Fab")
		)
		(fp_line
			(start -0.67945 -0.305054)
			(end -0.12065 -0.305054)
			(stroke
				(width 0.1)
				(type default)
			)
			(layer "F.Fab")
		)
		(pad "1" smd circle
			(at -0.40005 0 180)
			(size 0 0)
			(layers "F.Cu" "F.Mask" "F.Paste")
			(net "P3V3_AUX")
		)
		(pad "2" smd circle
			(at 0.40005 0 180)
			(size 0 0)
			(layers "F.Cu" "F.Mask" "F.Paste")
			(net "GND")
		)
	)
	(footprint ""
		(layer "F.Cu")
		(at 39.309294 -423.21734 180)
		(property "Reference" "R6153"
			(at 0 0 180)
			(layer "F.SilkS")
			(hide yes)
			(effects
				(font
					(size 1.27 1.27)
				)
			)
		)
		(property "Value" ""
			(at 0 0 180)
			(layer "F.Fab")
			(effects
				(font
					(size 1.27 1.27)
				)
			)
		)
		(duplicate_pad_numbers_are_jumpers no)
		(fp_line
			(start 0.32512 0.175006)
			(end -0.32512 0.175006)
			(stroke
				(width 0.1)
				(type default)
			)
			(layer "F.Fab")
		)
		(fp_line
			(start 0.32512 -0.175006)
			(end 0.32512 0.175006)
			(stroke
				(width 0.1)
				(type default)
			)
			(layer "F.Fab")
		)
		(fp_line
			(start -0.32512 0.175006)
			(end -0.32512 -0.175006)
			(stroke
				(width 0.1)
				(type default)
			)
			(layer "F.Fab")
		)
		(fp_line
			(start -0.32512 -0.175006)
			(end 0.32512 -0.175006)
			(stroke
				(width 0.1)
				(type default)
			)
			(layer "F.Fab")
		)
		(pad "1" smd rect
			(at -0.2667 0 180)
			(size 0.3048 0.381)
			(layers "F.Cu" "F.Mask" "F.Paste")
			(net "P2E_MB_BMC_TX_C_DN<0>")
		)
		(pad "2" smd rect
			(at 0.2667 0)
			(size 0.3048 0.381)
			(layers "F.Cu" "F.Mask" "F.Paste")
			(net "P2E_MB_BMC_TX_C_R1_DN<0>")
		)
	)
)
